# T6G (Grand Teton) — schematic netlist excerpt (pin names and nets, part order shuffled) for the footprints in the layout excerpt that follows; sources: Cadence DE-HDL packaged netlist, KiCad conversion of 04192023_DAF0TMB3IC0_F0TG_MB_C_brd_V02_OCP.brd

R6039  Q_RES  0 5% CHIP  pkg 0402LF  page 80 : A = OC_ALERT_N ; B = HSC_D_OC
R1649  Q_RES  1K 1% CHIP  pkg 0402LF  page 174 : A = PVDD18_S5_P0 ; B = CPU1_HDT_BYPASS_SEL

(kicad_pcb
	(version 20260206)
	(generator "pcbnew")
	(generator_version "10.0")
	(general
		(thickness 1.6)
		(legacy_teardrops no)
	)
	(paper "A4")
	(title_block
		(title "04192023_DAF0TMB3IC0_F0TG_MB_C_brd_V02_OCP.brd")
		(comment 1 "Grand Teton / footprints 1590-1591 of 8354")
	)
	(layers
		(0 "F.Cu" signal "TOP")
		(4 "In1.Cu" signal "GND")
		(6 "In2.Cu" signal "IN1")
		(8 "In3.Cu" signal "GND1")
		(10 "In4.Cu" signal "IN2")
		(12 "In5.Cu" signal "GND2")
		(14 "In6.Cu" signal "IN3")
		(16 "In7.Cu" signal "GND3")
		(18 "In8.Cu" signal "VCC")
		(20 "In9.Cu" signal "VCC1")
		(22 "In10.Cu" signal "GND4")
		(24 "In11.Cu" signal "IN4")
		(26 "In12.Cu" signal "GND5")
		(28 "In13.Cu" signal "IN5")
		(30 "In14.Cu" signal "GND6")
		(32 "In15.Cu" signal "IN6")
		(34 "In16.Cu" signal "GND7")
		(2 "B.Cu" signal "BOTTOM")
		(9 "F.Adhes" user "F.Adhesive")
		(11 "B.Adhes" user "B.Adhesive")
		(13 "F.Paste" user "Package Geometry/Pastemask Top")
		(15 "B.Paste" user "Package Geometry/Pastemask Bottom")
		(5 "F.SilkS" user "Ref Des/Silkscreen Top")
		(7 "B.SilkS" user "Ref Des/Silkscreen Bottom")
		(1 "F.Mask" user "Board Geometry/Soldermask Top")
		(3 "B.Mask" user "Board Geometry/Soldermask Bottom")
		(17 "Dwgs.User" user "User.Drawings")
		(19 "Cmts.User" user "User.Comments")
		(21 "Eco1.User" user "User.Eco1")
		(23 "Eco2.User" user "User.Eco2")
		(25 "Edge.Cuts" user "Board Geometry/Outline")
		(27 "Margin" user)
		(31 "F.CrtYd" user "Package Geometry/Place Bound Top")
		(29 "B.CrtYd" user "Package Geometry/Place Bound Bottom")
		(35 "F.Fab" user "Ref Des/Assembly Top")
		(33 "B.Fab" user "Ref Des/Assembly Bottom")
	)
	(footprint ""
		(layer "F.Cu")
		(at 213.835488 -136.31799 90)
		(property "Reference" "R1649"
			(at 0 0 90)
			(layer "F.SilkS")
			(hide yes)
			(effects
				(font
					(size 1.27 1.27)
				)
			)
		)
		(property "Value" ""
			(at 0 0 90)
			(layer "F.Fab")
			(effects
				(font
					(size 1.27 1.27)
				)
			)
		)
		(duplicate_pad_numbers_are_jumpers no)
		(fp_line
			(start 0.7874 -0.4064)
			(end 0.7874 0.4064)
			(stroke
				(width 0.1524)
				(type default)
			)
			(layer "F.SilkS")
		)
		(fp_line
			(start -0.7874 -0.4064)
			(end 0.7874 -0.4064)
			(stroke
				(width 0.1524)
				(type default)
			)
			(layer "F.SilkS")
		)
		(fp_line
			(start 0.7874 0.4064)
			(end -0.7874 0.4064)
			(stroke
				(width 0.1524)
				(type default)
			)
			(layer "F.SilkS")
		)
		(fp_line
			(start -0.7874 0.4064)
			(end -0.7874 -0.4064)
			(stroke
				(width 0.1524)
				(type default)
			)
			(layer "F.SilkS")
		)
		(fp_line
			(start -0.12065 -0.305054)
			(end -0.12065 -0.2794)
			(stroke
				(width 0.1)
				(type default)
			)
			(layer "F.Fab")
		)
		(fp_line
			(start -0.67945 -0.305054)
			(end -0.12065 -0.305054)
			(stroke
				(width 0.1)
				(type default)
			)
			(layer "F.Fab")
		)
		(fp_line
			(start 0.67945 -0.3048)
			(end 0.67945 0.3048)
			(stroke
				(width 0.1)
				(type default)
			)
			(layer "F.Fab")
		)
		(fp_line
			(start 0.12065 -0.3048)
			(end 0.67945 -0.3048)
			(stroke
				(width 0.1)
				(type default)
			)
			(layer "F.Fab")
		)
		(fp_line
			(start 0.12065 -0.2794)
			(end 0.12065 -0.3048)
			(stroke
				(width 0.1)
				(type default)
			)
			(layer "F.Fab")
		)
		(fp_line
			(start -0.12065 -0.2794)
			(end 0.12065 -0.2794)
			(stroke
				(width 0.1)
				(type default)
			)
			(layer "F.Fab")
		)
		(fp_line
			(start 0.120396 0.2794)
			(end -0.12065 0.2794)
			(stroke
				(width 0.1)
				(type default)
			)
			(layer "F.Fab")
		)
		(fp_line
			(start -0.12065 0.2794)
			(end -0.12065 0.3048)
			(stroke
				(width 0.1)
				(type default)
			)
			(layer "F.Fab")
		)
		(fp_line
			(start 0.67945 0.3048)
			(end 0.120396 0.3048)
			(stroke
				(width 0.1)
				(type default)
			)
			(layer "F.Fab")
		)
		(fp_line
			(start 0.120396 0.3048)
			(end 0.120396 0.2794)
			(stroke
				(width 0.1)
				(type default)
			)
			(layer "F.Fab")
		)
		(fp_line
			(start -0.12065 0.3048)
			(end -0.67945 0.3048)
			(stroke
				(width 0.1)
				(type default)
			)
			(layer "F.Fab")
		)
		(fp_line
			(start -0.67945 0.3048)
			(end -0.67945 -0.305054)
			(stroke
				(width 0.1)
				(type default)
			)
			(layer "F.Fab")
		)
		(pad "1" smd circle
			(at -0.40005 0 90)
			(size 0 0)
			(layers "F.Cu" "F.Mask" "F.Paste")
			(net "PVDD18_S5_P0")
		)
		(pad "2" smd circle
			(at 0.40005 0 90)
			(size 0 0)
			(layers "F.Cu" "F.Mask" "F.Paste")
			(net "CPU1_HDT_BYPASS_SEL")
		)
	)
	(footprint ""
		(layer "F.Cu")
		(at 163.703 -114.264948 180)
		(property "Reference" "R6039"
			(at 0 0 180)
			(layer "F.SilkS")
			(hide yes)
			(effects
				(font
					(size 1.27 1.27)
				)
			)
		)
		(property "Value" ""
			(at 0 0 180)
			(layer "F.Fab")
			(effects
				(font
					(size 1.27 1.27)
				)
			)
		)
		(duplicate_pad_numbers_are_jumpers no)
		(fp_line
			(start 0.7874 0.4064)
			(end -0.7874 0.4064)
			(stroke
				(width 0.1524)
				(type default)
			)
			(layer "F.SilkS")
		)
		(fp_line
			(start 0.7874 -0.4064)
			(end 0.7874 0.4064)
			(stroke
				(width 0.1524)
				(type default)
			)
			(layer "F.SilkS")
		)
		(fp_line
			(start -0.7874 0.4064)
			(end -0.7874 -0.4064)
			(stroke
				(width 0.1524)
				(type default)
			)
			(layer "F.SilkS")
		)
		(fp_line
			(start -0.7874 -0.4064)
			(end 0.7874 -0.4064)
			(stroke
				(width 0.1524)
				(type default)
			)
			(layer "F.SilkS")
		)
		(fp_line
			(start 0.67945 0.3048)
			(end 0.120396 0.3048)
			(stroke
				(width 0.1)
				(type default)
			)
			(layer "F.Fab")
		)
		(fp_line
			(start 0.67945 -0.3048)
			(end 0.67945 0.3048)
			(stroke
				(width 0.1)
				(type default)
			)
			(layer "F.Fab")
		)
		(fp_line
			(start 0.12065 -0.2794)
			(end 0.12065 -0.3048)
			(stroke
				(width 0.1)
				(type default)
			)
			(layer "F.Fab")
		)
		(fp_line
			(start 0.12065 -0.3048)
			(end 0.67945 -0.3048)
			(stroke
				(width 0.1)
				(type default)
			)
			(layer "F.Fab")
		)
		(fp_line
			(start 0.120396 0.3048)
			(end 0.120396 0.2794)
			(stroke
				(width 0.1)
				(type default)
			)
			(layer "F.Fab")
		)
		(fp_line
			(start 0.120396 0.2794)
			(end -0.12065 0.2794)
			(stroke
				(width 0.1)
				(type default)
			)
			(layer "F.Fab")
		)
		(fp_line
			(start -0.12065 0.3048)
			(end -0.67945 0.3048)
			(stroke
				(width 0.1)
				(type default)
			)
			(layer "F.Fab")
		)
		(fp_line
			(start -0.12065 0.2794)
			(end -0.12065 0.3048)
			(stroke
				(width 0.1)
				(type default)
			)
			(layer "F.Fab")
		)
		(fp_line
			(start -0.12065 -0.2794)
			(end 0.12065 -0.2794)
			(stroke
				(width 0.1)
				(type default)
			)
			(layer "F.Fab")
		)
		(fp_line
			(start -0.12065 -0.305054)
			(end -0.12065 -0.2794)
			(stroke
				(width 0.1)
				(type default)
			)
			(layer "F.Fab")
		)
		(fp_line
			(start -0.67945 0.3048)
			(end -0.67945 -0.305054)
			(stroke
				(width 0.1)
				(type default)
			)
			(layer "F.Fab")
		)
		(fp_line
			(start -0.67945 -0.305054)
			(end -0.12065 -0.305054)
			(stroke
				(width 0.1)
				(type default)
			)
			(layer "F.Fab")
		)
		(pad "1" smd circle
			(at -0.40005 0 180)
			(size 0 0)
			(layers "F.Cu" "F.Mask" "F.Paste")
			(net "OC_ALERT_N")
		)
		(pad "2" smd circle
			(at 0.40005 0 180)
			(size 0 0)
			(layers "F.Cu" "F.Mask" "F.Paste")
			(net "HSC_D_OC")
		)
	)
)
